# SCM (Grand Teton) — schematic netlist excerpt (pin names and nets, part order shuffled) for the footprints in the layout excerpt that follows; sources: Cadence DE-HDL packaged netlist, KiCad conversion of 12092022_DA0F0TMDCD0_F0T_Management_Board_D_brd_V3_OCP.brd

R627  Q_RES  4.7K 1% CHIP  pkg 0402LF  page 42 : A = P3V3_AUX ; B = PWRGD_DSW_PWROK
R55  Q_RES  4.7K 1% CHIP  pkg 0402LF  page 13 : A = P3V3_AUX ; B = FM_BMC_READY_R_PLD_N

(kicad_pcb
	(version 20260206)
	(generator "pcbnew")
	(generator_version "10.0")
	(general
		(thickness 1.6)
		(legacy_teardrops no)
	)
	(paper "A4")
	(title_block
		(title "12092022_DA0F0TMDCD0_F0T_Management_Board_D_brd_V3_OCP.brd")
		(comment 1 "Grand Teton / footprints 1021-1022 of 1440")
	)
	(layers
		(0 "F.Cu" signal "TOP")
		(4 "In1.Cu" signal "GND")
		(6 "In2.Cu" signal "IN1")
		(8 "In3.Cu" signal "GND1")
		(10 "In4.Cu" signal "IN2")
		(12 "In5.Cu" signal "VCC")
		(14 "In6.Cu" signal "VCC1")
		(16 "In7.Cu" signal "IN3")
		(18 "In8.Cu" signal "GND2")
		(20 "In9.Cu" signal "IN4")
		(22 "In10.Cu" signal "GND3")
		(2 "B.Cu" signal "BOTTOM")
		(9 "F.Adhes" user "F.Adhesive")
		(11 "B.Adhes" user "B.Adhesive")
		(13 "F.Paste" user "Package Geometry/Pastemask Top")
		(15 "B.Paste" user "Package Geometry/Pastemask Bottom")
		(5 "F.SilkS" user "Ref Des/Silkscreen Top")
		(7 "B.SilkS" user "Ref Des/Silkscreen Bottom")
		(1 "F.Mask" user "Board Geometry/Soldermask Top")
		(3 "B.Mask" user "Board Geometry/Soldermask Bottom")
		(17 "Dwgs.User" user "User.Drawings")
		(19 "Cmts.User" user "User.Comments")
		(21 "Eco1.User" user "User.Eco1")
		(23 "Eco2.User" user "User.Eco2")
		(25 "Edge.Cuts" user "Board Geometry/Outline")
		(27 "Margin" user)
		(31 "F.CrtYd" user "Package Geometry/Place Bound Top")
		(29 "B.CrtYd" user "Package Geometry/Place Bound Bottom")
		(35 "F.Fab" user "Ref Des/Assembly Top")
		(33 "B.Fab" user "Ref Des/Assembly Bottom")
	)
	(footprint ""
		(layer "B.Cu")
		(at 26.035 -101.981 -90)
		(property "Reference" "R627"
			(at 0 0 90)
			(layer "B.SilkS")
			(hide yes)
			(effects
				(font
					(size 1.27 1.27)
				)
				(justify mirror)
			)
		)
		(property "Value" ""
			(at 0 0 90)
			(layer "B.Fab")
			(effects
				(font
					(size 1.27 1.27)
				)
				(justify mirror)
			)
		)
		(duplicate_pad_numbers_are_jumpers no)
		(fp_line
			(start -0.7874 0.4064)
			(end 0.7874 0.4064)
			(stroke
				(width 0.1524)
				(type default)
			)
			(layer "B.SilkS")
		)
		(fp_line
			(start 0.7874 0.4064)
			(end 0.7874 -0.4064)
			(stroke
				(width 0.1524)
				(type default)
			)
			(layer "B.SilkS")
		)
		(fp_line
			(start -0.7874 -0.4064)
			(end -0.7874 0.4064)
			(stroke
				(width 0.1524)
				(type default)
			)
			(layer "B.SilkS")
		)
		(fp_line
			(start 0.7874 -0.4064)
			(end -0.7874 -0.4064)
			(stroke
				(width 0.1524)
				(type default)
			)
			(layer "B.SilkS")
		)
		(fp_line
			(start -0.67945 0.3048)
			(end -0.120396 0.3048)
			(stroke
				(width 0.1)
				(type default)
			)
			(layer "B.Fab")
		)
		(fp_line
			(start -0.120396 0.3048)
			(end -0.120396 0.2794)
			(stroke
				(width 0.1)
				(type default)
			)
			(layer "B.Fab")
		)
		(fp_line
			(start 0.12065 0.3048)
			(end 0.67945 0.3048)
			(stroke
				(width 0.1)
				(type default)
			)
			(layer "B.Fab")
		)
		(fp_line
			(start 0.67945 0.3048)
			(end 0.67945 -0.305054)
			(stroke
				(width 0.1)
				(type default)
			)
			(layer "B.Fab")
		)
		(fp_line
			(start -0.120396 0.2794)
			(end 0.12065 0.2794)
			(stroke
				(width 0.1)
				(type default)
			)
			(layer "B.Fab")
		)
		(fp_line
			(start 0.12065 0.2794)
			(end 0.12065 0.3048)
			(stroke
				(width 0.1)
				(type default)
			)
			(layer "B.Fab")
		)
		(fp_line
			(start -0.12065 -0.2794)
			(end -0.12065 -0.3048)
			(stroke
				(width 0.1)
				(type default)
			)
			(layer "B.Fab")
		)
		(fp_line
			(start 0.12065 -0.2794)
			(end -0.12065 -0.2794)
			(stroke
				(width 0.1)
				(type default)
			)
			(layer "B.Fab")
		)
		(fp_line
			(start -0.67945 -0.3048)
			(end -0.67945 0.3048)
			(stroke
				(width 0.1)
				(type default)
			)
			(layer "B.Fab")
		)
		(fp_line
			(start -0.12065 -0.3048)
			(end -0.67945 -0.3048)
			(stroke
				(width 0.1)
				(type default)
			)
			(layer "B.Fab")
		)
		(fp_line
			(start 0.12065 -0.305054)
			(end 0.12065 -0.2794)
			(stroke
				(width 0.1)
				(type default)
			)
			(layer "B.Fab")
		)
		(fp_line
			(start 0.67945 -0.305054)
			(end 0.12065 -0.305054)
			(stroke
				(width 0.1)
				(type default)
			)
			(layer "B.Fab")
		)
		(pad "1" smd circle
			(at 0.40005 0 90)
			(size 0 0)
			(layers "B.Cu" "B.Mask" "B.Paste")
			(net "P3V3_AUX")
		)
		(pad "2" smd circle
			(at -0.40005 0 90)
			(size 0 0)
			(layers "B.Cu" "B.Mask" "B.Paste")
			(net "PWRGD_DSW_PWROK")
		)
	)
	(footprint ""
		(layer "B.Cu")
		(at 50.927 -76.3016)
		(property "Reference" "R55"
			(at 0 0 0)
			(layer "B.SilkS")
			(hide yes)
			(effects
				(font
					(size 1.27 1.27)
				)
				(justify mirror)
			)
		)
		(property "Value" ""
			(at 0 0 0)
			(layer "B.Fab")
			(effects
				(font
					(size 1.27 1.27)
				)
				(justify mirror)
			)
		)
		(duplicate_pad_numbers_are_jumpers no)
		(fp_line
			(start -0.7874 -0.4064)
			(end -0.7874 0.4064)
			(stroke
				(width 0.1524)
				(type default)
			)
			(layer "B.SilkS")
		)
		(fp_line
			(start -0.7874 0.4064)
			(end 0.7874 0.4064)
			(stroke
				(width 0.1524)
				(type default)
			)
			(layer "B.SilkS")
		)
		(fp_line
			(start 0.7874 -0.4064)
			(end -0.7874 -0.4064)
			(stroke
				(width 0.1524)
				(type default)
			)
			(layer "B.SilkS")
		)
		(fp_line
			(start 0.7874 0.4064)
			(end 0.7874 -0.4064)
			(stroke
				(width 0.1524)
				(type default)
			)
			(layer "B.SilkS")
		)
		(fp_line
			(start -0.67945 -0.3048)
			(end -0.67945 0.3048)
			(stroke
				(width 0.1)
				(type default)
			)
			(layer "B.Fab")
		)
		(fp_line
			(start -0.67945 0.3048)
			(end -0.120396 0.3048)
			(stroke
				(width 0.1)
				(type default)
			)
			(layer "B.Fab")
		)
		(fp_line
			(start -0.12065 -0.3048)
			(end -0.67945 -0.3048)
			(stroke
				(width 0.1)
				(type default)
			)
			(layer "B.Fab")
		)
		(fp_line
			(start -0.12065 -0.2794)
			(end -0.12065 -0.3048)
			(stroke
				(width 0.1)
				(type default)
			)
			(layer "B.Fab")
		)
		(fp_line
			(start -0.120396 0.2794)
			(end 0.12065 0.2794)
			(stroke
				(width 0.1)
				(type default)
			)
			(layer "B.Fab")
		)
		(fp_line
			(start -0.120396 0.3048)
			(end -0.120396 0.2794)
			(stroke
				(width 0.1)
				(type default)
			)
			(layer "B.Fab")
		)
		(fp_line
			(start 0.12065 -0.305054)
			(end 0.12065 -0.2794)
			(stroke
				(width 0.1)
				(type default)
			)
			(layer "B.Fab")
		)
		(fp_line
			(start 0.12065 -0.2794)
			(end -0.12065 -0.2794)
			(stroke
				(width 0.1)
				(type default)
			)
			(layer "B.Fab")
		)
		(fp_line
			(start 0.12065 0.2794)
			(end 0.12065 0.3048)
			(stroke
				(width 0.1)
				(type default)
			)
			(layer "B.Fab")
		)
		(fp_line
			(start 0.12065 0.3048)
			(end 0.67945 0.3048)
			(stroke
				(width 0.1)
				(type default)
			)
			(layer "B.Fab")
		)
		(fp_line
			(start 0.67945 -0.305054)
			(end 0.12065 -0.305054)
			(stroke
				(width 0.1)
				(type default)
			)
			(layer "B.Fab")
		)
		(fp_line
			(start 0.67945 0.3048)
			(end 0.67945 -0.305054)
			(stroke
				(width 0.1)
				(type default)
			)
			(layer "B.Fab")
		)
		(pad "1" smd circle
			(at 0.40005 0 180)
			(size 0 0)
			(layers "B.Cu" "B.Mask" "B.Paste")
			(net "P3V3_AUX")
		)
		(pad "2" smd circle
			(at -0.40005 0 180)
			(size 0 0)
			(layers "B.Cu" "B.Mask" "B.Paste")
			(net "FM_BMC_READY_R_PLD_N")
		)
	)
)
